# T6G (Grand Teton) — schematic netlist excerpt (pin names and nets, part order shuffled) for the footprints in the layout excerpt that follows; sources: Cadence DE-HDL packaged netlist, KiCad conversion of 04192023_DAF0TMB3IC0_F0TG_MB_C_brd_V02_OCP.brd

R8247  Q_RES  1K 1% CHIP  pkg 0402LF  page 217 : A = PVDD18_S5_P1 ; B = PVDDCR_CPU1_P1_RESET_N_R
C2238  Q_CAP  22UF 4V 20% X6S  pkg C0402  page 69 : A = PVDDCR_CPU1_P0 ; B = GND

(kicad_pcb
	(version 20260206)
	(generator "pcbnew")
	(generator_version "10.0")
	(general
		(thickness 1.6)
		(legacy_teardrops no)
	)
	(paper "A4")
	(title_block
		(title "04192023_DAF0TMB3IC0_F0TG_MB_C_brd_V02_OCP.brd")
		(comment 1 "Grand Teton / footprints 5273-5274 of 8354")
	)
	(layers
		(0 "F.Cu" signal "TOP")
		(4 "In1.Cu" signal "GND")
		(6 "In2.Cu" signal "IN1")
		(8 "In3.Cu" signal "GND1")
		(10 "In4.Cu" signal "IN2")
		(12 "In5.Cu" signal "GND2")
		(14 "In6.Cu" signal "IN3")
		(16 "In7.Cu" signal "GND3")
		(18 "In8.Cu" signal "VCC")
		(20 "In9.Cu" signal "VCC1")
		(22 "In10.Cu" signal "GND4")
		(24 "In11.Cu" signal "IN4")
		(26 "In12.Cu" signal "GND5")
		(28 "In13.Cu" signal "IN5")
		(30 "In14.Cu" signal "GND6")
		(32 "In15.Cu" signal "IN6")
		(34 "In16.Cu" signal "GND7")
		(2 "B.Cu" signal "BOTTOM")
		(9 "F.Adhes" user "F.Adhesive")
		(11 "B.Adhes" user "B.Adhesive")
		(13 "F.Paste" user "Package Geometry/Pastemask Top")
		(15 "B.Paste" user "Package Geometry/Pastemask Bottom")
		(5 "F.SilkS" user "Ref Des/Silkscreen Top")
		(7 "B.SilkS" user "Ref Des/Silkscreen Bottom")
		(1 "F.Mask" user "Board Geometry/Soldermask Top")
		(3 "B.Mask" user "Board Geometry/Soldermask Bottom")
		(17 "Dwgs.User" user "User.Drawings")
		(19 "Cmts.User" user "User.Comments")
		(21 "Eco1.User" user "User.Eco1")
		(23 "Eco2.User" user "User.Eco2")
		(25 "Edge.Cuts" user "Board Geometry/Outline")
		(27 "Margin" user)
		(31 "F.CrtYd" user "Package Geometry/Place Bound Top")
		(29 "B.CrtYd" user "Package Geometry/Place Bound Bottom")
		(35 "F.Fab" user "Ref Des/Assembly Top")
		(33 "B.Fab" user "Ref Des/Assembly Bottom")
	)
	(footprint ""
		(layer "B.Cu")
		(at 350.215454 -268.41831)
		(property "Reference" "C2238"
			(at 0 0 0)
			(layer "B.SilkS")
			(hide yes)
			(effects
				(font
					(size 1.27 1.27)
				)
				(justify mirror)
			)
		)
		(property "Value" ""
			(at 0 0 0)
			(layer "B.Fab")
			(effects
				(font
					(size 1.27 1.27)
				)
				(justify mirror)
			)
		)
		(duplicate_pad_numbers_are_jumpers no)
		(fp_line
			(start -0.7874 -0.4064)
			(end -0.7874 0.4064)
			(stroke
				(width 0.1524)
				(type default)
			)
			(layer "B.SilkS")
		)
		(fp_line
			(start -0.7874 0.4064)
			(end 0.7874 0.4064)
			(stroke
				(width 0.1524)
				(type default)
			)
			(layer "B.SilkS")
		)
		(fp_line
			(start 0.7874 -0.4064)
			(end -0.7874 -0.4064)
			(stroke
				(width 0.1524)
				(type default)
			)
			(layer "B.SilkS")
		)
		(fp_line
			(start 0.7874 0.4064)
			(end 0.7874 -0.4064)
			(stroke
				(width 0.1524)
				(type default)
			)
			(layer "B.SilkS")
		)
		(fp_line
			(start -0.67945 -0.3048)
			(end -0.67945 0.3048)
			(stroke
				(width 0.1)
				(type default)
			)
			(layer "B.Fab")
		)
		(fp_line
			(start -0.67945 0.3048)
			(end -0.120396 0.3048)
			(stroke
				(width 0.1)
				(type default)
			)
			(layer "B.Fab")
		)
		(fp_line
			(start -0.12065 -0.3048)
			(end -0.67945 -0.3048)
			(stroke
				(width 0.1)
				(type default)
			)
			(layer "B.Fab")
		)
		(fp_line
			(start -0.12065 -0.2794)
			(end -0.12065 -0.3048)
			(stroke
				(width 0.1)
				(type default)
			)
			(layer "B.Fab")
		)
		(fp_line
			(start -0.120396 0.2794)
			(end 0.12065 0.2794)
			(stroke
				(width 0.1)
				(type default)
			)
			(layer "B.Fab")
		)
		(fp_line
			(start -0.120396 0.3048)
			(end -0.120396 0.2794)
			(stroke
				(width 0.1)
				(type default)
			)
			(layer "B.Fab")
		)
		(fp_line
			(start 0.12065 -0.305054)
			(end 0.12065 -0.2794)
			(stroke
				(width 0.1)
				(type default)
			)
			(layer "B.Fab")
		)
		(fp_line
			(start 0.12065 -0.2794)
			(end -0.12065 -0.2794)
			(stroke
				(width 0.1)
				(type default)
			)
			(layer "B.Fab")
		)
		(fp_line
			(start 0.12065 0.2794)
			(end 0.12065 0.3048)
			(stroke
				(width 0.1)
				(type default)
			)
			(layer "B.Fab")
		)
		(fp_line
			(start 0.12065 0.3048)
			(end 0.67945 0.3048)
			(stroke
				(width 0.1)
				(type default)
			)
			(layer "B.Fab")
		)
		(fp_line
			(start 0.67945 -0.305054)
			(end 0.12065 -0.305054)
			(stroke
				(width 0.1)
				(type default)
			)
			(layer "B.Fab")
		)
		(fp_line
			(start 0.67945 0.3048)
			(end 0.67945 -0.305054)
			(stroke
				(width 0.1)
				(type default)
			)
			(layer "B.Fab")
		)
		(pad "1" smd circle
			(at 0.40005 0 180)
			(size 0 0)
			(layers "B.Cu" "B.Mask" "B.Paste")
			(net "PVDDCR_CPU1_P0")
		)
		(pad "2" smd circle
			(at -0.40005 0 180)
			(size 0 0)
			(layers "B.Cu" "B.Mask" "B.Paste")
			(net "GND")
		)
	)
	(footprint ""
		(layer "B.Cu")
		(at 24.765 -363.347 180)
		(property "Reference" "R8247"
			(at 0 0 0)
			(layer "B.SilkS")
			(hide yes)
			(effects
				(font
					(size 1.27 1.27)
				)
				(justify mirror)
			)
		)
		(property "Value" ""
			(at 0 0 0)
			(layer "B.Fab")
			(effects
				(font
					(size 1.27 1.27)
				)
				(justify mirror)
			)
		)
		(duplicate_pad_numbers_are_jumpers no)
		(fp_line
			(start 0.7874 0.4064)
			(end 0.7874 -0.4064)
			(stroke
				(width 0.1524)
				(type default)
			)
			(layer "B.SilkS")
		)
		(fp_line
			(start 0.7874 -0.4064)
			(end -0.7874 -0.4064)
			(stroke
				(width 0.1524)
				(type default)
			)
			(layer "B.SilkS")
		)
		(fp_line
			(start -0.7874 0.4064)
			(end 0.7874 0.4064)
			(stroke
				(width 0.1524)
				(type default)
			)
			(layer "B.SilkS")
		)
		(fp_line
			(start -0.7874 -0.4064)
			(end -0.7874 0.4064)
			(stroke
				(width 0.1524)
				(type default)
			)
			(layer "B.SilkS")
		)
		(fp_line
			(start 0.67945 0.3048)
			(end 0.67945 -0.305054)
			(stroke
				(width 0.1)
				(type default)
			)
			(layer "B.Fab")
		)
		(fp_line
			(start 0.67945 -0.305054)
			(end 0.12065 -0.305054)
			(stroke
				(width 0.1)
				(type default)
			)
			(layer "B.Fab")
		)
		(fp_line
			(start 0.12065 0.3048)
			(end 0.67945 0.3048)
			(stroke
				(width 0.1)
				(type default)
			)
			(layer "B.Fab")
		)
		(fp_line
			(start 0.12065 0.2794)
			(end 0.12065 0.3048)
			(stroke
				(width 0.1)
				(type default)
			)
			(layer "B.Fab")
		)
		(fp_line
			(start 0.12065 -0.2794)
			(end -0.12065 -0.2794)
			(stroke
				(width 0.1)
				(type default)
			)
			(layer "B.Fab")
		)
		(fp_line
			(start 0.12065 -0.305054)
			(end 0.12065 -0.2794)
			(stroke
				(width 0.1)
				(type default)
			)
			(layer "B.Fab")
		)
		(fp_line
			(start -0.120396 0.3048)
			(end -0.120396 0.2794)
			(stroke
				(width 0.1)
				(type default)
			)
			(layer "B.Fab")
		)
		(fp_line
			(start -0.120396 0.2794)
			(end 0.12065 0.2794)
			(stroke
				(width 0.1)
				(type default)
			)
			(layer "B.Fab")
		)
		(fp_line
			(start -0.12065 -0.2794)
			(end -0.12065 -0.3048)
			(stroke
				(width 0.1)
				(type default)
			)
			(layer "B.Fab")
		)
		(fp_line
			(start -0.12065 -0.3048)
			(end -0.67945 -0.3048)
			(stroke
				(width 0.1)
				(type default)
			)
			(layer "B.Fab")
		)
		(fp_line
			(start -0.67945 0.3048)
			(end -0.120396 0.3048)
			(stroke
				(width 0.1)
				(type default)
			)
			(layer "B.Fab")
		)
		(fp_line
			(start -0.67945 -0.3048)
			(end -0.67945 0.3048)
			(stroke
				(width 0.1)
				(type default)
			)
			(layer "B.Fab")
		)
		(pad "1" smd circle
			(at 0.40005 0)
			(size 0 0)
			(layers "B.Cu" "B.Mask" "B.Paste")
			(net "PVDD18_S5_P1")
		)
		(pad "2" smd circle
			(at -0.40005 0)
			(size 0 0)
			(layers "B.Cu" "B.Mask" "B.Paste")
			(net "PVDDCR_CPU1_P1_RESET_N_R")
		)
	)
)
